(kicad_pcb
	(version 20260206)
	(generator "pcbnew")
	(generator_version "10.0")
	(general
		(thickness 1.6)
		(legacy_teardrops no)
	)
	(paper "A4")
	(title_block
		(title "Bryce Canyon_R.DPB_16317-1_OCP.brd")
		(comment 1 "Bryce Canyon / footprints 796-801 of 2099")
	)
	(layers
		(0 "F.Cu" signal "TOP")
		(4 "In1.Cu" signal "L2GND")
		(6 "In2.Cu" signal "L3")
		(8 "In3.Cu" signal "L4VCC")
		(10 "In4.Cu" signal "L5VCC")
		(12 "In5.Cu" signal "L6")
		(14 "In6.Cu" signal "L7GND")
		(2 "B.Cu" signal "BOTTOM")
		(9 "F.Adhes" user "F.Adhesive")
		(11 "B.Adhes" user "B.Adhesive")
		(13 "F.Paste" user "Package Geometry/Pastemask Top")
		(15 "B.Paste" user "Package Geometry/Pastemask Bottom")
		(5 "F.SilkS" user "Ref Des/Silkscreen Top")
		(7 "B.SilkS" user "Ref Des/Silkscreen Bottom")
		(1 "F.Mask" user "Board Geometry/Soldermask Top")
		(3 "B.Mask" user "Board Geometry/Soldermask Bottom")
		(17 "Dwgs.User" user "User.Drawings")
		(19 "Cmts.User" user "User.Comments")
		(21 "Eco1.User" user "User.Eco1")
		(23 "Eco2.User" user "User.Eco2")
		(25 "Edge.Cuts" user "Board Geometry/Outline")
		(27 "Margin" user)
		(31 "F.CrtYd" user "Package Geometry/Place Bound Top")
		(29 "B.CrtYd" user "Package Geometry/Place Bound Bottom")
		(35 "F.Fab" user "Ref Des/Assembly Top")
		(33 "B.Fab" user "Ref Des/Assembly Bottom")
	)
	(footprint ""
		(layer "F.Cu")
		(at 367.284 -243.586 180)
		(property "Reference" "R278"
			(at 0 0 180)
			(layer "F.SilkS")
			(hide yes)
			(effects
				(font
					(size 1.27 1.27)
				)
			)
		)
		(property "Value" "0R2J-2-GP"
			(at 0.064008 -3.993896 180)
			(unlocked yes)
			(layer "F.Fab")
			(hide yes)
			(effects
				(font
					(size 1.016 1.016)
					(thickness 0.1524)
				)
			)
		)
		(property "Device Type" "R402H16"
			(at 0.064008 -5.517896 180)
			(unlocked yes)
			(layer "F.Fab")
			(hide yes)
			(effects
				(font
					(size 1.016 1.016)
					(thickness 0.1524)
				)
			)
		)
		(duplicate_pad_numbers_are_jumpers no)
		(fp_line
			(start 0.508 -0.9398)
			(end -0.508 -0.9398)
			(stroke
				(width 0.1524)
				(type default)
			)
			(layer "F.SilkS")
		)
		(fp_line
			(start -0.508 -0.9398)
			(end -0.508 0.9398)
			(stroke
				(width 0.1524)
				(type default)
			)
			(layer "F.SilkS")
		)
		(fp_rect
			(start -0.508 0.9398)
			(end 0.508 -0.9398)
			(stroke
				(width 0)
				(type default)
			)
			(fill no)
			(layer "F.CrtYd")
		)
		(fp_rect
			(start -0.508 0.9398)
			(end 0.508 -0.9398)
			(stroke
				(width 0)
				(type default)
			)
			(fill no)
			(layer "F.Fab")
		)
		(pad "1" smd custom
			(at 0 -0.4445 180)
			(size 0.1397 0.1397)
			(layers "F.Cu" "F.Mask" "F.Paste")
			(net "DRIVE_B_7_PWR")
			(options
				(clearance outline)
				(anchor circle)
			)
			(primitives
				(gr_poly
					(pts
						(arc
							(start -0.1778 -0.2794)
							(mid -0.249642 -0.249642)
							(end -0.2794 -0.1778)
						)
						(arc
							(start -0.2794 0.1778)
							(mid -0.249642 0.249642)
							(end -0.1778 0.2794)
						)
						(arc
							(start 0.1778 0.2794)
							(mid 0.249642 0.249642)
							(end 0.2794 0.1778)
						)
						(arc
							(start 0.2794 -0.1778)
							(mid 0.249642 -0.249642)
							(end 0.1778 -0.2794)
						)
					)
					(width 0)
					(fill yes)
				)
			)
		)
		(pad "2" smd custom
			(at 0 0.4445 180)
			(size 0.1397 0.1397)
			(layers "F.Cu" "F.Mask" "F.Paste")
			(net "SW_PWR_R_HDD7")
			(options
				(clearance outline)
				(anchor circle)
			)
			(primitives
				(gr_poly
					(pts
						(arc
							(start -0.1778 -0.2794)
							(mid -0.249642 -0.249642)
							(end -0.2794 -0.1778)
						)
						(arc
							(start -0.2794 0.1778)
							(mid -0.249642 0.249642)
							(end -0.1778 0.2794)
						)
						(arc
							(start 0.1778 0.2794)
							(mid 0.249642 0.249642)
							(end 0.2794 0.1778)
						)
						(arc
							(start 0.2794 -0.1778)
							(mid 0.249642 -0.249642)
							(end 0.1778 -0.2794)
						)
					)
					(width 0)
					(fill yes)
				)
			)
		)
	)
	(footprint ""
		(layer "F.Cu")
		(at 209.92338 -247.88622)
		(property "Reference" "R43"
			(at 0 0 0)
			(layer "F.SilkS")
			(hide yes)
			(effects
				(font
					(size 1.27 1.27)
				)
			)
		)
		(property "Value" "4K7R2F-GP"
			(at 0.064008 -3.993896 0)
			(unlocked yes)
			(layer "F.Fab")
			(hide yes)
			(effects
				(font
					(size 1.016 1.016)
					(thickness 0.1524)
				)
			)
		)
		(property "Device Type" "R402H16"
			(at 0.064008 -5.517896 0)
			(unlocked yes)
			(layer "F.Fab")
			(hide yes)
			(effects
				(font
					(size 1.016 1.016)
					(thickness 0.1524)
				)
			)
		)
		(duplicate_pad_numbers_are_jumpers no)
		(fp_line
			(start -0.508 -0.9398)
			(end -0.508 0.9398)
			(stroke
				(width 0.1524)
				(type default)
			)
			(layer "F.SilkS")
		)
		(fp_line
			(start 0.508 -0.9398)
			(end -0.508 -0.9398)
			(stroke
				(width 0.1524)
				(type default)
			)
			(layer "F.SilkS")
		)
		(fp_rect
			(start -0.508 0.9398)
			(end 0.508 -0.9398)
			(stroke
				(width 0)
				(type default)
			)
			(fill no)
			(layer "F.CrtYd")
		)
		(fp_rect
			(start -0.508 0.9398)
			(end 0.508 -0.9398)
			(stroke
				(width 0)
				(type default)
			)
			(fill no)
			(layer "F.Fab")
		)
		(pad "1" smd custom
			(at 0 -0.4445)
			(size 0.1397 0.1397)
			(layers "F.Cu" "F.Mask" "F.Paste")
			(net "P3V3_STBY_B")
			(options
				(clearance outline)
				(anchor circle)
			)
			(primitives
				(gr_poly
					(pts
						(arc
							(start -0.1778 -0.2794)
							(mid -0.249642 -0.249642)
							(end -0.2794 -0.1778)
						)
						(arc
							(start -0.2794 0.1778)
							(mid -0.249642 0.249642)
							(end -0.1778 0.2794)
						)
						(arc
							(start 0.1778 0.2794)
							(mid 0.249642 0.249642)
							(end 0.2794 0.1778)
						)
						(arc
							(start 0.2794 -0.1778)
							(mid 0.249642 -0.249642)
							(end 0.1778 -0.2794)
						)
					)
					(width 0)
					(fill yes)
				)
			)
		)
		(pad "2" smd custom
			(at 0 0.4445)
			(size 0.1397 0.1397)
			(layers "F.Cu" "F.Mask" "F.Paste")
			(net "IO_EXP4_A2")
			(options
				(clearance outline)
				(anchor circle)
			)
			(primitives
				(gr_poly
					(pts
						(arc
							(start -0.1778 -0.2794)
							(mid -0.249642 -0.249642)
							(end -0.2794 -0.1778)
						)
						(arc
							(start -0.2794 0.1778)
							(mid -0.249642 0.249642)
							(end -0.1778 0.2794)
						)
						(arc
							(start 0.1778 0.2794)
							(mid 0.249642 0.249642)
							(end 0.2794 0.1778)
						)
						(arc
							(start 0.2794 -0.1778)
							(mid 0.249642 -0.249642)
							(end 0.1778 -0.2794)
						)
					)
					(width 0)
					(fill yes)
				)
			)
		)
	)
	(footprint ""
		(layer "F.Cu")
		(at 437.463184 -119.192548 180)
		(property "Reference" "R1170"
			(at 0 0 180)
			(layer "F.SilkS")
			(hide yes)
			(effects
				(font
					(size 1.27 1.27)
				)
			)
		)
		(property "Value" "0R2J-2-GP"
			(at 0.064008 -3.993896 180)
			(unlocked yes)
			(layer "F.Fab")
			(hide yes)
			(effects
				(font
					(size 1.016 1.016)
					(thickness 0.1524)
				)
			)
		)
		(property "Device Type" "R402H16"
			(at 0.064008 -5.517896 180)
			(unlocked yes)
			(layer "F.Fab")
			(hide yes)
			(effects
				(font
					(size 1.016 1.016)
					(thickness 0.1524)
				)
			)
		)
		(duplicate_pad_numbers_are_jumpers no)
		(fp_line
			(start 0.508 -0.9398)
			(end -0.508 -0.9398)
			(stroke
				(width 0.1524)
				(type default)
			)
			(layer "F.SilkS")
		)
		(fp_line
			(start -0.508 -0.9398)
			(end -0.508 0.9398)
			(stroke
				(width 0.1524)
				(type default)
			)
			(layer "F.SilkS")
		)
		(fp_rect
			(start -0.508 0.9398)
			(end 0.508 -0.9398)
			(stroke
				(width 0)
				(type default)
			)
			(fill no)
			(layer "F.CrtYd")
		)
		(fp_rect
			(start -0.508 0.9398)
			(end 0.508 -0.9398)
			(stroke
				(width 0)
				(type default)
			)
			(fill no)
			(layer "F.Fab")
		)
		(pad "1" smd custom
			(at 0 -0.4445 180)
			(size 0.1397 0.1397)
			(layers "F.Cu" "F.Mask" "F.Paste")
			(net "P5V_B_4_ROVP")
			(options
				(clearance outline)
				(anchor circle)
			)
			(primitives
				(gr_poly
					(pts
						(arc
							(start -0.1778 -0.2794)
							(mid -0.249642 -0.249642)
							(end -0.2794 -0.1778)
						)
						(arc
							(start -0.2794 0.1778)
							(mid -0.249642 0.249642)
							(end -0.1778 0.2794)
						)
						(arc
							(start 0.1778 0.2794)
							(mid 0.249642 0.249642)
							(end 0.2794 0.1778)
						)
						(arc
							(start 0.2794 -0.1778)
							(mid 0.249642 -0.249642)
							(end 0.1778 -0.2794)
						)
					)
					(width 0)
					(fill yes)
				)
			)
		)
		(pad "2" smd custom
			(at 0 0.4445 180)
			(size 0.1397 0.1397)
			(layers "F.Cu" "F.Mask" "F.Paste")
			(net "AGND_P5V_B_4")
			(options
				(clearance outline)
				(anchor circle)
			)
			(primitives
				(gr_poly
					(pts
						(arc
							(start -0.1778 -0.2794)
							(mid -0.249642 -0.249642)
							(end -0.2794 -0.1778)
						)
						(arc
							(start -0.2794 0.1778)
							(mid -0.249642 0.249642)
							(end -0.1778 0.2794)
						)
						(arc
							(start 0.1778 0.2794)
							(mid 0.249642 0.249642)
							(end 0.2794 0.1778)
						)
						(arc
							(start 0.2794 -0.1778)
							(mid 0.249642 -0.249642)
							(end 0.1778 -0.2794)
						)
					)
					(width 0)
					(fill yes)
				)
			)
		)
	)
	(footprint ""
		(layer "F.Cu")
		(at 336.804 -148.082)
		(property "Reference" "Q84"
			(at 0 0 0)
			(layer "F.SilkS")
			(hide yes)
			(effects
				(font
					(size 1.27 1.27)
				)
			)
		)
		(property "Value" "AO4407AL-GP"
			(at -3.707384 -1.5367 0)
			(unlocked yes)
			(layer "F.Fab")
			(hide yes)
			(effects
				(font
					(size 1.016 1.016)
					(thickness 0.1524)
				)
			)
		)
		(property "Device Type" "SOIC8H69"
			(at -3.707384 -3.0607 0)
			(unlocked yes)
			(layer "F.Fab")
			(hide yes)
			(effects
				(font
					(size 1.016 1.016)
					(thickness 0.1524)
				)
			)
		)
		(duplicate_pad_numbers_are_jumpers no)
		(fp_line
			(start -2.7432 -1.4224)
			(end -2.7432 1.4224)
			(stroke
				(width 0.1524)
				(type default)
			)
			(layer "F.SilkS")
		)
		(fp_line
			(start -2.7432 1.4224)
			(end -2.6416 1.4224)
			(stroke
				(width 0.1524)
				(type default)
			)
			(layer "F.SilkS")
		)
		(fp_line
			(start -2.7432 1.4224)
			(end 2.1336 1.4224)
			(stroke
				(width 0.1524)
				(type default)
			)
			(layer "F.SilkS")
		)
		(fp_line
			(start -2.7178 -0.508)
			(end -2.1844 -0.0508)
			(stroke
				(width 0.1524)
				(type default)
			)
			(layer "F.SilkS")
		)
		(fp_line
			(start -2.6289 3.4417)
			(end -2.6289 1.4732)
			(stroke
				(width 0.381)
				(type default)
			)
			(layer "F.SilkS")
		)
		(fp_line
			(start -2.1844 -0.0508)
			(end -2.7178 0.508)
			(stroke
				(width 0.1524)
				(type default)
			)
			(layer "F.SilkS")
		)
		(fp_line
			(start 2.1336 -1.4224)
			(end -2.7432 -1.4224)
			(stroke
				(width 0.1524)
				(type default)
			)
			(layer "F.SilkS")
		)
		(fp_line
			(start 2.1336 1.4224)
			(end 2.1336 -1.4224)
			(stroke
				(width 0.1524)
				(type default)
			)
			(layer "F.SilkS")
		)
		(fp_poly
			(pts
				(xy -2.2098 -1.4224) (xy -2.2098 1.4224) (xy 2.2098 1.4224) (xy 2.2098 -1.4224)
			)
			(stroke
				(width 0)
				(type default)
			)
			(fill yes)
			(layer "F.SilkS")
		)
		(fp_rect
			(start -2.450084 2.999994)
			(end 2.450084 -2.999994)
			(stroke
				(width 0)
				(type default)
			)
			(fill no)
			(layer "F.CrtYd")
		)
		(fp_poly
			(pts
				(xy -2.8194 3.6322) (xy -2.8194 -3.6322) (xy 2.8194 -3.6322) (xy 2.8194 1.18364) (xy 2.450084 1.18364)
				(xy 2.450084 -2.999994) (xy -2.450084 -2.999994) (xy -2.450084 2.999994) (xy 2.450084 2.999994)
				(xy 2.450084 1.18618) (xy 2.8194 1.18618) (xy 2.8194 3.6322)
			)
			(stroke
				(width 0)
				(type default)
			)
			(fill no)
			(layer "F.CrtYd")
		)
		(fp_rect
			(start -2.8194 3.6322)
			(end 2.8194 -3.6322)
			(stroke
				(width 0)
				(type default)
			)
			(fill no)
			(layer "F.Fab")
		)
		(pad "1" smd rect
			(at -1.905 2.54)
			(size 0.635 1.651)
			(layers "F.Cu" "F.Mask" "F.Paste")
			(net "P12V_B")
		)
		(pad "2" smd rect
			(at -0.635 2.54)
			(size 0.635 1.651)
			(layers "F.Cu" "F.Mask" "F.Paste")
			(net "P12V_B")
		)
		(pad "3" smd rect
			(at 0.635 2.54)
			(size 0.635 1.651)
			(layers "F.Cu" "F.Mask" "F.Paste")
			(net "P12V_B")
		)
		(pad "4" smd rect
			(at 1.905 2.54)
			(size 0.635 1.651)
			(layers "F.Cu" "F.Mask" "F.Paste")
			(net "SW_HDD_N18")
		)
		(pad "5" smd rect
			(at 1.905 -2.54)
			(size 0.635 1.651)
			(layers "F.Cu" "F.Mask" "F.Paste")
			(net "P12V_HDD18")
		)
		(pad "6" smd rect
			(at 0.635 -2.54)
			(size 0.635 1.651)
			(layers "F.Cu" "F.Mask" "F.Paste")
			(net "P12V_HDD18")
		)
		(pad "7" smd rect
			(at -0.635 -2.54)
			(size 0.635 1.651)
			(layers "F.Cu" "F.Mask" "F.Paste")
			(net "P12V_HDD18")
		)
		(pad "8" smd rect
			(at -1.905 -2.54)
			(size 0.635 1.651)
			(layers "F.Cu" "F.Mask" "F.Paste")
			(net "P12V_HDD18")
		)
	)
	(footprint ""
		(layer "F.Cu")
		(at 246.619522 -363.702346 90)
		(property "Reference" "R1026"
			(at 0 0 90)
			(layer "F.SilkS")
			(hide yes)
			(effects
				(font
					(size 1.27 1.27)
				)
			)
		)
		(property "Value" "10R2F-L-GP"
			(at 0.064008 -3.993896 90)
			(unlocked yes)
			(layer "F.Fab")
			(hide yes)
			(effects
				(font
					(size 1.016 1.016)
					(thickness 0.1524)
				)
			)
		)
		(property "Device Type" "R402H14"
			(at 0.064008 -5.517896 90)
			(unlocked yes)
			(layer "F.Fab")
			(hide yes)
			(effects
				(font
					(size 1.016 1.016)
					(thickness 0.1524)
				)
			)
		)
		(duplicate_pad_numbers_are_jumpers no)
		(fp_line
			(start 0.508 -0.9398)
			(end -0.508 -0.9398)
			(stroke
				(width 0.1524)
				(type default)
			)
			(layer "F.SilkS")
		)
		(fp_line
			(start -0.508 -0.9398)
			(end -0.508 0.9398)
			(stroke
				(width 0.1524)
				(type default)
			)
			(layer "F.SilkS")
		)
		(fp_rect
			(start -0.508 0.9398)
			(end 0.508 -0.9398)
			(stroke
				(width 0)
				(type default)
			)
			(fill no)
			(layer "F.CrtYd")
		)
		(fp_rect
			(start -0.508 0.9398)
			(end 0.508 -0.9398)
			(stroke
				(width 0)
				(type default)
			)
			(fill no)
			(layer "F.Fab")
		)
		(pad "1" smd custom
			(at 0 -0.4445 90)
			(size 0.1397 0.1397)
			(layers "F.Cu" "F.Mask" "F.Paste")
			(net "P12V_IN")
			(options
				(clearance outline)
				(anchor circle)
			)
			(primitives
				(gr_poly
					(pts
						(arc
							(start -0.1778 -0.2794)
							(mid -0.249642 -0.249642)
							(end -0.2794 -0.1778)
						)
						(arc
							(start -0.2794 0.1778)
							(mid -0.249642 0.249642)
							(end -0.1778 0.2794)
						)
						(arc
							(start 0.1778 0.2794)
							(mid 0.249642 0.249642)
							(end 0.2794 0.1778)
						)
						(arc
							(start 0.2794 -0.1778)
							(mid 0.249642 -0.249642)
							(end 0.1778 -0.2794)
						)
					)
					(width 0)
					(fill yes)
				)
			)
		)
		(pad "2" smd custom
			(at 0 0.4445 90)
			(size 0.1397 0.1397)
			(layers "F.Cu" "F.Mask" "F.Paste")
			(net "MB3_P12V_HS")
			(options
				(clearance outline)
				(anchor circle)
			)
			(primitives
				(gr_poly
					(pts
						(arc
							(start -0.1778 -0.2794)
							(mid -0.249642 -0.249642)
							(end -0.2794 -0.1778)
						)
						(arc
							(start -0.2794 0.1778)
							(mid -0.249642 0.249642)
							(end -0.1778 0.2794)
						)
						(arc
							(start 0.1778 0.2794)
							(mid 0.249642 0.249642)
							(end 0.2794 0.1778)
						)
						(arc
							(start 0.2794 -0.1778)
							(mid 0.249642 -0.249642)
							(end 0.1778 -0.2794)
						)
					)
					(width 0)
					(fill yes)
				)
			)
		)
	)
	(footprint ""
		(layer "F.Cu")
		(at 96.324928 -63.799974)
		(property "Reference" ""
			(at 0 0 0)
			(layer "F.SilkS")
			(hide yes)
			(effects
				(font
					(size 1.27 1.27)
				)
			)
		)
		(property "Value" "*"
			(at -8.398764 -8.057642 0)
			(unlocked yes)
			(layer "F.Fab")
			(hide yes)
			(effects
				(font
					(size 1.016 1.016)
					(thickness 0.1524)
				)
			)
		)
		(duplicate_pad_numbers_are_jumpers no)
		(fp_poly
			(pts
				(arc
					(start 7.3152 0)
					(mid 0 7.3152)
					(end -7.3152 0)
				)
				(arc
					(start -7.3152 -5.9944)
					(mid 0 -13.3096)
					(end 7.3152 -5.9944)
				)
			)
			(stroke
				(width 0)
				(type default)
			)
			(fill no)
			(layer "B.CrtYd")
		)
		(fp_poly
			(pts
				(arc
					(start 7.3152 0)
					(mid 0 7.3152)
					(end -7.3152 0)
				)
				(arc
					(start -7.3152 -5.9944)
					(mid 0 -13.3096)
					(end 7.3152 -5.9944)
				)
			)
			(stroke
				(width 0)
				(type default)
			)
			(fill no)
			(layer "F.CrtYd")
		)
		(fp_poly
			(pts
				(arc
					(start 7.3152 0)
					(mid 0 7.3152)
					(end -7.3152 0)
				)
				(arc
					(start -7.3152 -5.9944)
					(mid 0 -13.3096)
					(end 7.3152 -5.9944)
				)
			)
			(stroke
				(width 0)
				(type default)
			)
			(fill no)
			(layer "B.Fab")
		)
		(fp_poly
			(pts
				(arc
					(start 7.3152 0)
					(mid 0 7.3152)
					(end -7.3152 0)
				)
				(arc
					(start -7.3152 -5.9944)
					(mid 0 -13.3096)
					(end 7.3152 -5.9944)
				)
			)
			(stroke
				(width 0)
				(type default)
			)
			(fill no)
			(layer "F.Fab")
		)
		(pad "1" thru_hole oval
			(at 0 0)
			(size 14.0208 20.0152)
			(drill 0.0254
				(offset 0 -2.9972)
			)
			(layers "*.Cu" "*.Mask")
			(remove_unused_layers no)
			(net "Net_48")
			(clearance -1.002284)
			(thermal_gap 0.1524)
			(padstack
				(mode front_inner_back)
				(layer "Inner"
					(shape custom)
					(size 2.928012 2.928012)
					(options
						(anchor circle)
					)
					(primitives
						(gr_poly
							(pts
								(arc
									(start 4.571746 -2.084324)
									(mid 0.000333 7.430372)
									(end -4.571492 -2.084324)
								)
								(arc
									(start -4.571492 -2.084324)
									(mid -3.570296 -3.611977)
									(end -2.875026 -5.30098)
								)
								(arc
									(start -2.875026 -5.30098)
									(mid 0.000217 -7.43089)
									(end 2.87528 -5.30098)
								)
								(arc
									(start 2.87528 -5.30098)
									(mid 3.570511 -3.611956)
									(end 4.571746 -2.084324)
								)
							)
							(width 0)
							(fill yes)
						)
					)
					(clearance 0.1524)
				)
				(layer "B.Cu"
					(shape oval)
					(size 14.0208 20.0152)
					(offset 0 -2.9972)
					(clearance -1.002284)
				)
			)
		)
		(zone
			(layers "F.Cu" "B.Cu" "In1.Cu" "In2.Cu" "In3.Cu" "In4.Cu" "In5.Cu" "In6.Cu")
			(hatch none 0.5)
			(connect_pads
				(clearance 0)
			)
			(min_thickness 0.25)
			(keepout
				(tracks not_allowed)
				(vias allowed)
				(pads allowed)
				(copperpour not_allowed)
				(footprints allowed)
			)
			(placement
				(enabled no)
				(sheetname "")
			)
			(fill
				(thermal_gap 0.5)
				(thermal_bridge_width 0.5)
				(island_removal_mode 0)
			)
			(polygon
				(pts
					(arc
						(start 89.314528 -69.794374)
						(mid 96.324928 -76.804774)
						(end 103.335328 -69.794374)
					)
					(arc
						(start 103.335328 -63.799974)
						(mid 96.324928 -56.789574)
						(end 89.314528 -63.799974)
					)
				)
			)
		)
	)
)
